(kicad_pcb
	(version 20260206)
	(generator "pcbnew")
	(generator_version "10.0")
	(general
		(thickness 1.6)
		(legacy_teardrops no)
	)
	(paper "A4")
	(title_block
		(title "04192023_DAF0TMB3IC0_F0TG_MB_C_brd_V02_OCP.brd")
		(comment 1 "Grand Teton / footprint 3955 of 8354 (U25), pads 328-434 of 6102")
	)
	(layers
		(0 "F.Cu" signal "TOP")
		(4 "In1.Cu" signal "GND")
		(6 "In2.Cu" signal "IN1")
		(8 "In3.Cu" signal "GND1")
		(10 "In4.Cu" signal "IN2")
		(12 "In5.Cu" signal "GND2")
		(14 "In6.Cu" signal "IN3")
		(16 "In7.Cu" signal "GND3")
		(18 "In8.Cu" signal "VCC")
		(20 "In9.Cu" signal "VCC1")
		(22 "In10.Cu" signal "GND4")
		(24 "In11.Cu" signal "IN4")
		(26 "In12.Cu" signal "GND5")
		(28 "In13.Cu" signal "IN5")
		(30 "In14.Cu" signal "GND6")
		(32 "In15.Cu" signal "IN6")
		(34 "In16.Cu" signal "GND7")
		(2 "B.Cu" signal "BOTTOM")
		(9 "F.Adhes" user "F.Adhesive")
		(11 "B.Adhes" user "B.Adhesive")
		(13 "F.Paste" user "Package Geometry/Pastemask Top")
		(15 "B.Paste" user "Package Geometry/Pastemask Bottom")
		(5 "F.SilkS" user "Ref Des/Silkscreen Top")
		(7 "B.SilkS" user "Ref Des/Silkscreen Bottom")
		(1 "F.Mask" user "Board Geometry/Soldermask Top")
		(3 "B.Mask" user "Board Geometry/Soldermask Bottom")
		(17 "Dwgs.User" user "User.Drawings")
		(19 "Cmts.User" user "User.Comments")
		(21 "Eco1.User" user "User.Eco1")
		(23 "Eco2.User" user "User.Eco2")
		(25 "Edge.Cuts" user "Board Geometry/Outline")
		(27 "Margin" user)
		(31 "F.CrtYd" user "Package Geometry/Place Bound Top")
		(29 "B.CrtYd" user "Package Geometry/Place Bound Bottom")
		(35 "F.Fab" user "Ref Des/Assembly Top")
		(33 "B.Fab" user "Ref Des/Assembly Bottom")
	)
	(footprint ""
		(layer "F.Cu")
		(at 359.867962 -258.880102 180)
		(property "Reference" "U25"
			(at -45.78477 -62.086744 0)
			(unlocked yes)
			(layer "F.SilkS")
			(effects
				(font
					(size 0.7874 0.5842)
					(thickness 0.1524)
				)
			)
		)
		(property "Value" ""
			(at 0 0 180)
			(layer "F.Fab")
			(effects
				(font
					(size 1.27 1.27)
				)
			)
		)
		(duplicate_pad_numbers_are_jumpers no)
		(pad "AD52" smd circle
			(at 13.310108 -18.18005 180)
			(size 0.450088 0.450088)
			(layers "F.Cu" "F.Mask" "F.Paste")
			(net "GND")
		)
		(pad "AD53" smd circle
			(at 14.249908 -18.18005 180)
			(size 0.450088 0.450088)
			(layers "F.Cu" "F.Mask" "F.Paste")
			(net "GND")
		)
		(pad "AD54" smd circle
			(at 15.189962 -18.18005 180)
			(size 0.450088 0.450088)
			(layers "F.Cu" "F.Mask" "F.Paste")
			(net "PVDDIO_P0")
		)
		(pad "AD55" smd circle
			(at 16.130016 -18.18005 180)
			(size 0.450088 0.450088)
			(layers "F.Cu" "F.Mask" "F.Paste")
			(net "M_C_CPU0_SA_DQ<25>")
		)
		(pad "AD56" smd circle
			(at 17.07007 -18.18005 180)
			(size 0.450088 0.450088)
			(layers "F.Cu" "F.Mask" "F.Paste")
			(net "M_C_CPU0_SA_DQ<26>")
		)
		(pad "AD57" smd circle
			(at 18.010124 -18.18005 180)
			(size 0.450088 0.450088)
			(layers "F.Cu" "F.Mask" "F.Paste")
			(net "GND")
		)
		(pad "AD58" smd circle
			(at 18.949924 -18.18005 180)
			(size 0.450088 0.450088)
			(layers "F.Cu" "F.Mask" "F.Paste")
			(net "M_D_CPU0_SA_DQ<25>")
		)
		(pad "AD59" smd circle
			(at 19.889978 -18.18005 180)
			(size 0.450088 0.450088)
			(layers "F.Cu" "F.Mask" "F.Paste")
			(net "GND")
		)
		(pad "AD60" smd circle
			(at 20.830032 -18.18005 180)
			(size 0.450088 0.450088)
			(layers "F.Cu" "F.Mask" "F.Paste")
			(net "M_D_CPU0_SA_DQ<26>")
		)
		(pad "AD61" smd circle
			(at 21.770086 -18.18005 180)
			(size 0.450088 0.450088)
			(layers "F.Cu" "F.Mask" "F.Paste")
			(net "GND")
		)
		(pad "AD62" smd circle
			(at 22.709886 -18.18005 180)
			(size 0.450088 0.450088)
			(layers "F.Cu" "F.Mask" "F.Paste")
			(net "M_B_CPU0_SA_DQ<25>")
		)
		(pad "AD63" smd circle
			(at 23.64994 -18.18005 180)
			(size 0.450088 0.450088)
			(layers "F.Cu" "F.Mask" "F.Paste")
			(net "M_B_CPU0_SA_DQ<26>")
		)
		(pad "AD64" smd circle
			(at 24.589994 -18.18005 180)
			(size 0.450088 0.450088)
			(layers "F.Cu" "F.Mask" "F.Paste")
			(net "GND")
		)
		(pad "AD65" smd circle
			(at 25.530048 -18.18005 180)
			(size 0.450088 0.450088)
			(layers "F.Cu" "F.Mask" "F.Paste")
			(net "M_F_CPU0_SA_DQ<25>")
		)
		(pad "AD66" smd circle
			(at 26.470102 -18.18005 180)
			(size 0.450088 0.450088)
			(layers "F.Cu" "F.Mask" "F.Paste")
			(net "GND")
		)
		(pad "AD67" smd circle
			(at 27.409902 -18.18005 180)
			(size 0.450088 0.450088)
			(layers "F.Cu" "F.Mask" "F.Paste")
			(net "M_F_CPU0_SA_DQ<26>")
		)
		(pad "AD68" smd circle
			(at 28.349956 -18.18005 180)
			(size 0.450088 0.450088)
			(layers "F.Cu" "F.Mask" "F.Paste")
			(net "GND")
		)
		(pad "AD69" smd circle
			(at 29.29001 -18.18005 180)
			(size 0.450088 0.450088)
			(layers "F.Cu" "F.Mask" "F.Paste")
			(net "M_E_CPU0_SA_DQ<25>")
		)
		(pad "AD70" smd circle
			(at 30.230064 -18.18005 180)
			(size 0.450088 0.450088)
			(layers "F.Cu" "F.Mask" "F.Paste")
			(net "M_E_CPU0_SA_DQ<26>")
		)
		(pad "AD71" smd circle
			(at 31.170118 -18.18005 180)
			(size 0.450088 0.450088)
			(layers "F.Cu" "F.Mask" "F.Paste")
			(net "GND")
		)
		(pad "AD72" smd circle
			(at 32.109918 -18.18005 180)
			(size 0.450088 0.450088)
			(layers "F.Cu" "F.Mask" "F.Paste")
			(net "M_A_CPU0_SA_DQ<25>")
		)
		(pad "AD73" smd circle
			(at 33.049972 -18.18005 180)
			(size 0.450088 0.450088)
			(layers "F.Cu" "F.Mask" "F.Paste")
			(net "GND")
		)
		(pad "AD74" smd circle
			(at 33.990026 -18.18005 180)
			(size 0.450088 0.450088)
			(layers "F.Cu" "F.Mask" "F.Paste")
			(net "M_A_CPU0_SA_DQ<26>")
		)
		(pad "AE1" smd circle
			(at -34.159952 -17.370044 180)
			(size 0.450088 0.450088)
			(layers "F.Cu" "F.Mask" "F.Paste")
			(net "GND")
		)
		(pad "AE2" smd circle
			(at -33.219898 -17.370044 180)
			(size 0.450088 0.450088)
			(layers "F.Cu" "F.Mask" "F.Paste")
			(net "M_G_CPU0_SA_DQS_DP<3>")
		)
		(pad "AE3" smd circle
			(at -32.280098 -17.370044 180)
			(size 0.450088 0.450088)
			(layers "F.Cu" "F.Mask" "F.Paste")
			(net "M_G_CPU0_SA_DQ<27>")
		)
		(pad "AE4" smd circle
			(at -31.340044 -17.370044 180)
			(size 0.450088 0.450088)
			(layers "F.Cu" "F.Mask" "F.Paste")
			(net "GND")
		)
		(pad "AE5" smd circle
			(at -30.39999 -17.370044 180)
			(size 0.450088 0.450088)
			(layers "F.Cu" "F.Mask" "F.Paste")
			(net "M_K_CPU0_SA_DQS_DP<3>")
		)
		(pad "AE6" smd circle
			(at -29.459936 -17.370044 180)
			(size 0.450088 0.450088)
			(layers "F.Cu" "F.Mask" "F.Paste")
			(net "GND")
		)
		(pad "AE7" smd circle
			(at -28.519882 -17.370044 180)
			(size 0.450088 0.450088)
			(layers "F.Cu" "F.Mask" "F.Paste")
			(net "M_K_CPU0_SA_DQ<27>")
		)
		(pad "AE8" smd circle
			(at -27.580082 -17.370044 180)
			(size 0.450088 0.450088)
			(layers "F.Cu" "F.Mask" "F.Paste")
			(net "GND")
		)
		(pad "AE9" smd circle
			(at -26.640028 -17.370044 180)
			(size 0.450088 0.450088)
			(layers "F.Cu" "F.Mask" "F.Paste")
			(net "M_L_CPU0_SA_DQS_DP<3>")
		)
		(pad "AE10" smd circle
			(at -25.699974 -17.370044 180)
			(size 0.450088 0.450088)
			(layers "F.Cu" "F.Mask" "F.Paste")
			(net "M_L_CPU0_SA_DQ<27>")
		)
		(pad "AE11" smd circle
			(at -24.75992 -17.370044 180)
			(size 0.450088 0.450088)
			(layers "F.Cu" "F.Mask" "F.Paste")
			(net "GND")
		)
		(pad "AE12" smd circle
			(at -23.82012 -17.370044 180)
			(size 0.450088 0.450088)
			(layers "F.Cu" "F.Mask" "F.Paste")
			(net "M_H_CPU0_SA_DQS_DP<3>")
		)
		(pad "AE13" smd circle
			(at -22.880066 -17.370044 180)
			(size 0.450088 0.450088)
			(layers "F.Cu" "F.Mask" "F.Paste")
			(net "GND")
		)
		(pad "AE14" smd circle
			(at -21.940012 -17.370044 180)
			(size 0.450088 0.450088)
			(layers "F.Cu" "F.Mask" "F.Paste")
			(net "M_H_CPU0_SA_DQ<27>")
		)
		(pad "AE15" smd circle
			(at -20.999958 -17.370044 180)
			(size 0.450088 0.450088)
			(layers "F.Cu" "F.Mask" "F.Paste")
			(net "GND")
		)
		(pad "AE16" smd circle
			(at -20.059904 -17.370044 180)
			(size 0.450088 0.450088)
			(layers "F.Cu" "F.Mask" "F.Paste")
			(net "M_J_CPU0_SA_DQS_DP<3>")
		)
		(pad "AE17" smd circle
			(at -19.120104 -17.370044 180)
			(size 0.450088 0.450088)
			(layers "F.Cu" "F.Mask" "F.Paste")
			(net "M_J_CPU0_SA_DQ<27>")
		)
		(pad "AE18" smd circle
			(at -18.18005 -17.370044 180)
			(size 0.450088 0.450088)
			(layers "F.Cu" "F.Mask" "F.Paste")
			(net "GND")
		)
		(pad "AE19" smd circle
			(at -17.239996 -17.370044 180)
			(size 0.450088 0.450088)
			(layers "F.Cu" "F.Mask" "F.Paste")
			(net "M_I_CPU0_SA_DQS_DP<3>")
		)
		(pad "AE20" smd circle
			(at -16.299942 -17.370044 180)
			(size 0.450088 0.450088)
			(layers "F.Cu" "F.Mask" "F.Paste")
			(net "GND")
		)
		(pad "AE21" smd circle
			(at -15.359888 -17.370044 180)
			(size 0.450088 0.450088)
			(layers "F.Cu" "F.Mask" "F.Paste")
			(net "M_I_CPU0_SA_DQ<27>")
		)
		(pad "AE22" smd circle
			(at -14.420088 -17.370044 180)
			(size 0.450088 0.450088)
			(layers "F.Cu" "F.Mask" "F.Paste")
			(net "GND")
		)
		(pad "AE23" smd circle
			(at -13.480034 -17.370044 180)
			(size 0.450088 0.450088)
			(layers "F.Cu" "F.Mask" "F.Paste")
			(net "GMI_CPU1_G0_CPU0_G2_TX_DN<0>")
		)
		(pad "AE24" smd circle
			(at -12.53998 -17.370044 180)
			(size 0.450088 0.450088)
			(layers "F.Cu" "F.Mask" "F.Paste")
			(net "GMI_CPU1_G0_CPU0_G2_TX_DP<0>")
		)
		(pad "AE25" smd circle
			(at -11.599926 -17.370044 180)
			(size 0.450088 0.450088)
			(layers "F.Cu" "F.Mask" "F.Paste")
			(net "GND")
		)
		(pad "AE26" smd circle
			(at -10.659872 -17.370044 180)
			(size 0.450088 0.450088)
			(layers "F.Cu" "F.Mask" "F.Paste")
			(net "GMI_CPU1_G0_CPU0_G2_TX_DN<3>")
		)
		(pad "AE27" smd circle
			(at -9.720072 -17.370044 180)
			(size 0.450088 0.450088)
			(layers "F.Cu" "F.Mask" "F.Paste")
			(net "GMI_CPU1_G0_CPU0_G2_TX_DP<3>")
		)
		(pad "AE28" smd circle
			(at -8.780018 -17.370044 180)
			(size 0.450088 0.450088)
			(layers "F.Cu" "F.Mask" "F.Paste")
			(net "GND")
		)
		(pad "AE29" smd circle
			(at -7.839964 -17.370044 180)
			(size 0.450088 0.450088)
			(layers "F.Cu" "F.Mask" "F.Paste")
			(net "GMI_CPU1_G0_CPU0_G2_TX_DN<6>")
		)
		(pad "AE30" smd circle
			(at -6.89991 -17.370044 180)
			(size 0.450088 0.450088)
			(layers "F.Cu" "F.Mask" "F.Paste")
			(net "GMI_CPU1_G0_CPU0_G2_TX_DP<6>")
		)
		(pad "AE31" smd circle
			(at -5.96011 -17.370044 180)
			(size 0.450088 0.450088)
			(layers "F.Cu" "F.Mask" "F.Paste")
			(net "GND")
		)
		(pad "AE32" smd circle
			(at -5.020056 -17.370044 180)
			(size 0.450088 0.450088)
			(layers "F.Cu" "F.Mask" "F.Paste")
			(net "GMI_CPU1_G0_CPU0_G2_TX_DN<9>")
		)
		(pad "AE33" smd circle
			(at -4.080002 -17.370044 180)
			(size 0.450088 0.450088)
			(layers "F.Cu" "F.Mask" "F.Paste")
			(net "GMI_CPU1_G0_CPU0_G2_TX_DP<9>")
		)
		(pad "AE34" smd circle
			(at -3.139948 -17.370044 180)
			(size 0.450088 0.450088)
			(layers "F.Cu" "F.Mask" "F.Paste")
			(net "GND")
		)
		(pad "AE35" smd circle
			(at -2.199894 -17.370044 180)
			(size 0.450088 0.450088)
			(layers "F.Cu" "F.Mask" "F.Paste")
			(net "GND")
		)
		(pad "AE36" smd circle
			(at -1.260094 -17.370044 180)
			(size 0.450088 0.450088)
			(layers "F.Cu" "F.Mask" "F.Paste")
			(net "GND")
		)
		(pad "AE40" smd circle
			(at 1.560068 -17.370044 180)
			(size 0.450088 0.450088)
			(layers "F.Cu" "F.Mask" "F.Paste")
			(net "GND")
		)
		(pad "AE41" smd circle
			(at 2.500122 -17.370044 180)
			(size 0.450088 0.450088)
			(layers "F.Cu" "F.Mask" "F.Paste")
			(net "GND")
		)
		(pad "AE42" smd circle
			(at 3.439922 -17.370044 180)
			(size 0.450088 0.450088)
			(layers "F.Cu" "F.Mask" "F.Paste")
			(net "GND")
		)
		(pad "AE43" smd circle
			(at 4.379976 -17.370044 180)
			(size 0.450088 0.450088)
			(layers "F.Cu" "F.Mask" "F.Paste")
			(net "GMI_CPU0_G0_CPU1_G2_TX_DP<6>")
		)
		(pad "AE44" smd circle
			(at 5.32003 -17.370044 180)
			(size 0.450088 0.450088)
			(layers "F.Cu" "F.Mask" "F.Paste")
			(net "GMI_CPU0_G0_CPU1_G2_TX_DN<6>")
		)
		(pad "AE45" smd circle
			(at 6.260084 -17.370044 180)
			(size 0.450088 0.450088)
			(layers "F.Cu" "F.Mask" "F.Paste")
			(net "GND")
		)
		(pad "AE46" smd circle
			(at 7.199884 -17.370044 180)
			(size 0.450088 0.450088)
			(layers "F.Cu" "F.Mask" "F.Paste")
			(net "GMI_CPU0_G0_CPU1_G2_TX_DP<9>")
		)
		(pad "AE47" smd circle
			(at 8.139938 -17.370044 180)
			(size 0.450088 0.450088)
			(layers "F.Cu" "F.Mask" "F.Paste")
			(net "GMI_CPU0_G0_CPU1_G2_TX_DN<9>")
		)
		(pad "AE48" smd circle
			(at 9.079992 -17.370044 180)
			(size 0.450088 0.450088)
			(layers "F.Cu" "F.Mask" "F.Paste")
			(net "GND")
		)
		(pad "AE49" smd circle
			(at 10.020046 -17.370044 180)
			(size 0.450088 0.450088)
			(layers "F.Cu" "F.Mask" "F.Paste")
			(net "GMI_CPU0_G0_CPU1_G2_TX_DP<12>")
		)
		(pad "AE50" smd circle
			(at 10.9601 -17.370044 180)
			(size 0.450088 0.450088)
			(layers "F.Cu" "F.Mask" "F.Paste")
			(net "GMI_CPU0_G0_CPU1_G2_TX_DN<12>")
		)
		(pad "AE51" smd circle
			(at 11.8999 -17.370044 180)
			(size 0.450088 0.450088)
			(layers "F.Cu" "F.Mask" "F.Paste")
			(net "GND")
		)
		(pad "AE52" smd circle
			(at 12.839954 -17.370044 180)
			(size 0.450088 0.450088)
			(layers "F.Cu" "F.Mask" "F.Paste")
			(net "GMI_CPU0_G0_CPU1_G2_TX_DP<15>")
		)
		(pad "AE53" smd circle
			(at 13.780008 -17.370044 180)
			(size 0.450088 0.450088)
			(layers "F.Cu" "F.Mask" "F.Paste")
			(net "GMI_CPU0_G0_CPU1_G2_TX_DN<15>")
		)
		(pad "AE54" smd circle
			(at 14.720062 -17.370044 180)
			(size 0.450088 0.450088)
			(layers "F.Cu" "F.Mask" "F.Paste")
			(net "GND")
		)
		(pad "AE55" smd circle
			(at 15.660116 -17.370044 180)
			(size 0.450088 0.450088)
			(layers "F.Cu" "F.Mask" "F.Paste")
			(net "M_C_CPU0_SA_DQ<27>")
		)
		(pad "AE56" smd circle
			(at 16.599916 -17.370044 180)
			(size 0.450088 0.450088)
			(layers "F.Cu" "F.Mask" "F.Paste")
			(net "GND")
		)
		(pad "AE57" smd circle
			(at 17.53997 -17.370044 180)
			(size 0.450088 0.450088)
			(layers "F.Cu" "F.Mask" "F.Paste")
			(net "M_C_CPU0_SA_DQS_DP<3>")
		)
		(pad "AE58" smd circle
			(at 18.480024 -17.370044 180)
			(size 0.450088 0.450088)
			(layers "F.Cu" "F.Mask" "F.Paste")
			(net "GND")
		)
		(pad "AE59" smd circle
			(at 19.420078 -17.370044 180)
			(size 0.450088 0.450088)
			(layers "F.Cu" "F.Mask" "F.Paste")
			(net "M_D_CPU0_SA_DQ<27>")
		)
		(pad "AE60" smd circle
			(at 20.359878 -17.370044 180)
			(size 0.450088 0.450088)
			(layers "F.Cu" "F.Mask" "F.Paste")
			(net "M_D_CPU0_SA_DQS_DP<3>")
		)
		(pad "AE61" smd circle
			(at 21.299932 -17.370044 180)
			(size 0.450088 0.450088)
			(layers "F.Cu" "F.Mask" "F.Paste")
			(net "GND")
		)
		(pad "AE62" smd circle
			(at 22.239986 -17.370044 180)
			(size 0.450088 0.450088)
			(layers "F.Cu" "F.Mask" "F.Paste")
			(net "M_B_CPU0_SA_DQ<27>")
		)
		(pad "AE63" smd circle
			(at 23.18004 -17.370044 180)
			(size 0.450088 0.450088)
			(layers "F.Cu" "F.Mask" "F.Paste")
			(net "GND")
		)
		(pad "AE64" smd circle
			(at 24.120094 -17.370044 180)
			(size 0.450088 0.450088)
			(layers "F.Cu" "F.Mask" "F.Paste")
			(net "M_B_CPU0_SA_DQS_DP<3>")
		)
		(pad "AE65" smd circle
			(at 25.059894 -17.370044 180)
			(size 0.450088 0.450088)
			(layers "F.Cu" "F.Mask" "F.Paste")
			(net "GND")
		)
		(pad "AE66" smd circle
			(at 25.999948 -17.370044 180)
			(size 0.450088 0.450088)
			(layers "F.Cu" "F.Mask" "F.Paste")
			(net "M_F_CPU0_SA_DQ<27>")
		)
		(pad "AE67" smd circle
			(at 26.940002 -17.370044 180)
			(size 0.450088 0.450088)
			(layers "F.Cu" "F.Mask" "F.Paste")
			(net "M_F_CPU0_SA_DQS_DP<3>")
		)
		(pad "AE68" smd circle
			(at 27.880056 -17.370044 180)
			(size 0.450088 0.450088)
			(layers "F.Cu" "F.Mask" "F.Paste")
			(net "GND")
		)
		(pad "AE69" smd circle
			(at 28.82011 -17.370044 180)
			(size 0.450088 0.450088)
			(layers "F.Cu" "F.Mask" "F.Paste")
			(net "M_E_CPU0_SA_DQ<27>")
		)
		(pad "AE70" smd circle
			(at 29.75991 -17.370044 180)
			(size 0.450088 0.450088)
			(layers "F.Cu" "F.Mask" "F.Paste")
			(net "GND")
		)
		(pad "AE71" smd circle
			(at 30.699964 -17.370044 180)
			(size 0.450088 0.450088)
			(layers "F.Cu" "F.Mask" "F.Paste")
			(net "M_E_CPU0_SA_DQS_DP<3>")
		)
		(pad "AE72" smd circle
			(at 31.640018 -17.370044 180)
			(size 0.450088 0.450088)
			(layers "F.Cu" "F.Mask" "F.Paste")
			(net "GND")
		)
		(pad "AE73" smd circle
			(at 32.580072 -17.370044 180)
			(size 0.450088 0.450088)
			(layers "F.Cu" "F.Mask" "F.Paste")
			(net "M_A_CPU0_SA_DQ<27>")
		)
		(pad "AE74" smd circle
			(at 33.519872 -17.370044 180)
			(size 0.450088 0.450088)
			(layers "F.Cu" "F.Mask" "F.Paste")
			(net "M_A_CPU0_SA_DQS_DP<3>")
		)
		(pad "AE75" smd circle
			(at 34.459926 -17.370044 180)
			(size 0.450088 0.450088)
			(layers "F.Cu" "F.Mask" "F.Paste")
			(net "GND")
		)
		(pad "AF2" smd circle
			(at -33.690052 -16.560038 180)
			(size 0.450088 0.450088)
			(layers "F.Cu" "F.Mask" "F.Paste")
			(net "M_G_CPU0_SA_DQS_DN<3>")
		)
		(pad "AF3" smd circle
			(at -32.749998 -16.560038 180)
			(size 0.450088 0.450088)
			(layers "F.Cu" "F.Mask" "F.Paste")
			(net "GND")
		)
		(pad "AF4" smd circle
			(at -31.809944 -16.560038 180)
			(size 0.450088 0.450088)
			(layers "F.Cu" "F.Mask" "F.Paste")
			(net "M_G_CPU0_SA_DQS_DN<8>")
		)
		(pad "AF5" smd circle
			(at -30.86989 -16.560038 180)
			(size 0.450088 0.450088)
			(layers "F.Cu" "F.Mask" "F.Paste")
			(net "PVDDCR_SOC_P0")
		)
		(pad "AF6" smd circle
			(at -29.93009 -16.560038 180)
			(size 0.450088 0.450088)
			(layers "F.Cu" "F.Mask" "F.Paste")
			(net "M_K_CPU0_SA_DQS_DN<3>")
		)
		(pad "AF7" smd circle
			(at -28.990036 -16.560038 180)
			(size 0.450088 0.450088)
			(layers "F.Cu" "F.Mask" "F.Paste")
			(net "M_K_CPU0_SA_DQS_DN<8>")
		)
		(pad "AF8" smd circle
			(at -28.049982 -16.560038 180)
			(size 0.450088 0.450088)
			(layers "F.Cu" "F.Mask" "F.Paste")
			(net "GND")
		)
		(pad "AF9" smd circle
			(at -27.109928 -16.560038 180)
			(size 0.450088 0.450088)
			(layers "F.Cu" "F.Mask" "F.Paste")
			(net "M_L_CPU0_SA_DQS_DN<3>")
		)
		(pad "AF10" smd circle
			(at -26.170128 -16.560038 180)
			(size 0.450088 0.450088)
			(layers "F.Cu" "F.Mask" "F.Paste")
			(net "GND")
		)
		(pad "AF11" smd circle
			(at -25.230074 -16.560038 180)
			(size 0.450088 0.450088)
			(layers "F.Cu" "F.Mask" "F.Paste")
			(net "M_L_CPU0_SA_DQS_DN<8>")
		)
		(pad "AF12" smd circle
			(at -24.29002 -16.560038 180)
			(size 0.450088 0.450088)
			(layers "F.Cu" "F.Mask" "F.Paste")
			(net "PVDDCR_SOC_P0")
		)
		(pad "AF13" smd circle
			(at -23.349966 -16.560038 180)
			(size 0.450088 0.450088)
			(layers "F.Cu" "F.Mask" "F.Paste")
			(net "M_H_CPU0_SA_DQS_DN<3>")
		)
	)
)
